(kicad_pcb
	(version 20260206)
	(generator "pcbnew")
	(generator_version "10.0")
	(general
		(thickness 1.6)
		(legacy_teardrops no)
	)
	(paper "A4")
	(title_block
		(title "03242023_DA0F0TMBIJ0_F0T_Motherboard_J_brd_V01_OCP.brd")
		(comment 1 "Grand Teton / footprints 1302-1307 of 6105")
	)
	(layers
		(0 "F.Cu" signal "TOP")
		(4 "In1.Cu" signal "GND")
		(6 "In2.Cu" signal "IN1")
		(8 "In3.Cu" signal "GND1")
		(10 "In4.Cu" signal "IN2")
		(12 "In5.Cu" signal "GND2")
		(14 "In6.Cu" signal "IN3")
		(16 "In7.Cu" signal "GND3")
		(18 "In8.Cu" signal "VCC")
		(20 "In9.Cu" signal "VCC1")
		(22 "In10.Cu" signal "GND4")
		(24 "In11.Cu" signal "IN4")
		(26 "In12.Cu" signal "GND5")
		(28 "In13.Cu" signal "IN5")
		(30 "In14.Cu" signal "GND6")
		(32 "In15.Cu" signal "IN6")
		(34 "In16.Cu" signal "GND7")
		(2 "B.Cu" signal "BOTTOM")
		(9 "F.Adhes" user "F.Adhesive")
		(11 "B.Adhes" user "B.Adhesive")
		(13 "F.Paste" user "Package Geometry/Pastemask Top")
		(15 "B.Paste" user "Package Geometry/Pastemask Bottom")
		(5 "F.SilkS" user "Ref Des/Silkscreen Top")
		(7 "B.SilkS" user "Ref Des/Silkscreen Bottom")
		(1 "F.Mask" user "Board Geometry/Soldermask Top")
		(3 "B.Mask" user "Board Geometry/Soldermask Bottom")
		(17 "Dwgs.User" user "User.Drawings")
		(19 "Cmts.User" user "User.Comments")
		(21 "Eco1.User" user "User.Eco1")
		(23 "Eco2.User" user "User.Eco2")
		(25 "Edge.Cuts" user "Board Geometry/Outline")
		(27 "Margin" user)
		(31 "F.CrtYd" user "Package Geometry/Place Bound Top")
		(29 "B.CrtYd" user "Package Geometry/Place Bound Bottom")
		(35 "F.Fab" user "Ref Des/Assembly Top")
		(33 "B.Fab" user "Ref Des/Assembly Bottom")
	)
	(footprint ""
		(layer "F.Cu")
		(at 112.78108 -106.238548 -90)
		(property "Reference" "R4042"
			(at 0 0 270)
			(layer "F.SilkS")
			(hide yes)
			(effects
				(font
					(size 1.27 1.27)
				)
			)
		)
		(property "Value" ""
			(at 0 0 270)
			(layer "F.Fab")
			(effects
				(font
					(size 1.27 1.27)
				)
			)
		)
		(duplicate_pad_numbers_are_jumpers no)
		(fp_line
			(start -0.7874 0.4064)
			(end -0.7874 -0.4064)
			(stroke
				(width 0.1524)
				(type default)
			)
			(layer "F.SilkS")
		)
		(fp_line
			(start 0.7874 0.4064)
			(end -0.7874 0.4064)
			(stroke
				(width 0.1524)
				(type default)
			)
			(layer "F.SilkS")
		)
		(fp_line
			(start -0.7874 -0.4064)
			(end 0.7874 -0.4064)
			(stroke
				(width 0.1524)
				(type default)
			)
			(layer "F.SilkS")
		)
		(fp_line
			(start 0.7874 -0.4064)
			(end 0.7874 0.4064)
			(stroke
				(width 0.1524)
				(type default)
			)
			(layer "F.SilkS")
		)
		(fp_line
			(start -0.67945 0.3048)
			(end -0.67945 -0.305054)
			(stroke
				(width 0.1)
				(type default)
			)
			(layer "F.Fab")
		)
		(fp_line
			(start -0.12065 0.3048)
			(end -0.67945 0.3048)
			(stroke
				(width 0.1)
				(type default)
			)
			(layer "F.Fab")
		)
		(fp_line
			(start 0.120396 0.3048)
			(end 0.120396 0.2794)
			(stroke
				(width 0.1)
				(type default)
			)
			(layer "F.Fab")
		)
		(fp_line
			(start 0.67945 0.3048)
			(end 0.120396 0.3048)
			(stroke
				(width 0.1)
				(type default)
			)
			(layer "F.Fab")
		)
		(fp_line
			(start -0.12065 0.2794)
			(end -0.12065 0.3048)
			(stroke
				(width 0.1)
				(type default)
			)
			(layer "F.Fab")
		)
		(fp_line
			(start 0.120396 0.2794)
			(end -0.12065 0.2794)
			(stroke
				(width 0.1)
				(type default)
			)
			(layer "F.Fab")
		)
		(fp_line
			(start -0.12065 -0.2794)
			(end 0.12065 -0.2794)
			(stroke
				(width 0.1)
				(type default)
			)
			(layer "F.Fab")
		)
		(fp_line
			(start 0.12065 -0.2794)
			(end 0.12065 -0.3048)
			(stroke
				(width 0.1)
				(type default)
			)
			(layer "F.Fab")
		)
		(fp_line
			(start 0.12065 -0.3048)
			(end 0.67945 -0.3048)
			(stroke
				(width 0.1)
				(type default)
			)
			(layer "F.Fab")
		)
		(fp_line
			(start 0.67945 -0.3048)
			(end 0.67945 0.3048)
			(stroke
				(width 0.1)
				(type default)
			)
			(layer "F.Fab")
		)
		(fp_line
			(start -0.67945 -0.305054)
			(end -0.12065 -0.305054)
			(stroke
				(width 0.1)
				(type default)
			)
			(layer "F.Fab")
		)
		(fp_line
			(start -0.12065 -0.305054)
			(end -0.12065 -0.2794)
			(stroke
				(width 0.1)
				(type default)
			)
			(layer "F.Fab")
		)
		(pad "1" smd circle
			(at -0.40005 0 270)
			(size 0 0)
			(layers "F.Cu" "F.Mask" "F.Paste")
			(net "RST_CPU0_DRAM_AB_PLD_LVT3_R_N")
		)
		(pad "2" smd circle
			(at 0.40005 0 270)
			(size 0 0)
			(layers "F.Cu" "F.Mask" "F.Paste")
			(net "RST_CPU0_DRAM_AB_PLD_LVT3_N")
		)
	)
	(footprint ""
		(layer "F.Cu")
		(at 201.8284 -92.6338 -90)
		(property "Reference" "C2379"
			(at 0 0 270)
			(layer "F.SilkS")
			(hide yes)
			(effects
				(font
					(size 1.27 1.27)
				)
			)
		)
		(property "Value" ""
			(at 0 0 270)
			(layer "F.Fab")
			(effects
				(font
					(size 1.27 1.27)
				)
			)
		)
		(duplicate_pad_numbers_are_jumpers no)
		(fp_line
			(start -0.7874 0.4064)
			(end -0.7874 -0.4064)
			(stroke
				(width 0.1524)
				(type default)
			)
			(layer "F.SilkS")
		)
		(fp_line
			(start 0.7874 0.4064)
			(end -0.7874 0.4064)
			(stroke
				(width 0.1524)
				(type default)
			)
			(layer "F.SilkS")
		)
		(fp_line
			(start -0.7874 -0.4064)
			(end 0.7874 -0.4064)
			(stroke
				(width 0.1524)
				(type default)
			)
			(layer "F.SilkS")
		)
		(fp_line
			(start 0.7874 -0.4064)
			(end 0.7874 0.4064)
			(stroke
				(width 0.1524)
				(type default)
			)
			(layer "F.SilkS")
		)
		(fp_line
			(start -0.67945 0.3048)
			(end -0.67945 -0.305054)
			(stroke
				(width 0.1)
				(type default)
			)
			(layer "F.Fab")
		)
		(fp_line
			(start -0.12065 0.3048)
			(end -0.67945 0.3048)
			(stroke
				(width 0.1)
				(type default)
			)
			(layer "F.Fab")
		)
		(fp_line
			(start 0.120396 0.3048)
			(end 0.120396 0.2794)
			(stroke
				(width 0.1)
				(type default)
			)
			(layer "F.Fab")
		)
		(fp_line
			(start 0.67945 0.3048)
			(end 0.120396 0.3048)
			(stroke
				(width 0.1)
				(type default)
			)
			(layer "F.Fab")
		)
		(fp_line
			(start -0.12065 0.2794)
			(end -0.12065 0.3048)
			(stroke
				(width 0.1)
				(type default)
			)
			(layer "F.Fab")
		)
		(fp_line
			(start 0.120396 0.2794)
			(end -0.12065 0.2794)
			(stroke
				(width 0.1)
				(type default)
			)
			(layer "F.Fab")
		)
		(fp_line
			(start -0.12065 -0.2794)
			(end 0.12065 -0.2794)
			(stroke
				(width 0.1)
				(type default)
			)
			(layer "F.Fab")
		)
		(fp_line
			(start 0.12065 -0.2794)
			(end 0.12065 -0.3048)
			(stroke
				(width 0.1)
				(type default)
			)
			(layer "F.Fab")
		)
		(fp_line
			(start 0.12065 -0.3048)
			(end 0.67945 -0.3048)
			(stroke
				(width 0.1)
				(type default)
			)
			(layer "F.Fab")
		)
		(fp_line
			(start 0.67945 -0.3048)
			(end 0.67945 0.3048)
			(stroke
				(width 0.1)
				(type default)
			)
			(layer "F.Fab")
		)
		(fp_line
			(start -0.67945 -0.305054)
			(end -0.12065 -0.305054)
			(stroke
				(width 0.1)
				(type default)
			)
			(layer "F.Fab")
		)
		(fp_line
			(start -0.12065 -0.305054)
			(end -0.12065 -0.2794)
			(stroke
				(width 0.1)
				(type default)
			)
			(layer "F.Fab")
		)
		(pad "1" smd circle
			(at -0.40005 0 270)
			(size 0 0)
			(layers "F.Cu" "F.Mask" "F.Paste")
			(net "UV_ADR_P2V5_COMP")
		)
		(pad "2" smd circle
			(at 0.40005 0 270)
			(size 0 0)
			(layers "F.Cu" "F.Mask" "F.Paste")
			(net "GND")
		)
	)
	(footprint ""
		(layer "F.Cu")
		(at 422.273984 -364.563914 90)
		(property "Reference" "PC1171"
			(at 0 0 90)
			(layer "F.SilkS")
			(hide yes)
			(effects
				(font
					(size 1.27 1.27)
				)
			)
		)
		(property "Value" ""
			(at 0 0 90)
			(layer "F.Fab")
			(effects
				(font
					(size 1.27 1.27)
				)
			)
		)
		(duplicate_pad_numbers_are_jumpers no)
		(fp_line
			(start 0.7874 -0.4064)
			(end 0.7874 0.4064)
			(stroke
				(width 0.1524)
				(type default)
			)
			(layer "F.SilkS")
		)
		(fp_line
			(start -0.7874 -0.4064)
			(end 0.7874 -0.4064)
			(stroke
				(width 0.1524)
				(type default)
			)
			(layer "F.SilkS")
		)
		(fp_line
			(start 0.7874 0.4064)
			(end -0.7874 0.4064)
			(stroke
				(width 0.1524)
				(type default)
			)
			(layer "F.SilkS")
		)
		(fp_line
			(start -0.7874 0.4064)
			(end -0.7874 -0.4064)
			(stroke
				(width 0.1524)
				(type default)
			)
			(layer "F.SilkS")
		)
		(fp_line
			(start -0.12065 -0.305054)
			(end -0.12065 -0.2794)
			(stroke
				(width 0.1)
				(type default)
			)
			(layer "F.Fab")
		)
		(fp_line
			(start -0.67945 -0.305054)
			(end -0.12065 -0.305054)
			(stroke
				(width 0.1)
				(type default)
			)
			(layer "F.Fab")
		)
		(fp_line
			(start 0.67945 -0.3048)
			(end 0.67945 0.3048)
			(stroke
				(width 0.1)
				(type default)
			)
			(layer "F.Fab")
		)
		(fp_line
			(start 0.12065 -0.3048)
			(end 0.67945 -0.3048)
			(stroke
				(width 0.1)
				(type default)
			)
			(layer "F.Fab")
		)
		(fp_line
			(start 0.12065 -0.2794)
			(end 0.12065 -0.3048)
			(stroke
				(width 0.1)
				(type default)
			)
			(layer "F.Fab")
		)
		(fp_line
			(start -0.12065 -0.2794)
			(end 0.12065 -0.2794)
			(stroke
				(width 0.1)
				(type default)
			)
			(layer "F.Fab")
		)
		(fp_line
			(start 0.120396 0.2794)
			(end -0.12065 0.2794)
			(stroke
				(width 0.1)
				(type default)
			)
			(layer "F.Fab")
		)
		(fp_line
			(start -0.12065 0.2794)
			(end -0.12065 0.3048)
			(stroke
				(width 0.1)
				(type default)
			)
			(layer "F.Fab")
		)
		(fp_line
			(start 0.67945 0.3048)
			(end 0.120396 0.3048)
			(stroke
				(width 0.1)
				(type default)
			)
			(layer "F.Fab")
		)
		(fp_line
			(start 0.120396 0.3048)
			(end 0.120396 0.2794)
			(stroke
				(width 0.1)
				(type default)
			)
			(layer "F.Fab")
		)
		(fp_line
			(start -0.12065 0.3048)
			(end -0.67945 0.3048)
			(stroke
				(width 0.1)
				(type default)
			)
			(layer "F.Fab")
		)
		(fp_line
			(start -0.67945 0.3048)
			(end -0.67945 -0.305054)
			(stroke
				(width 0.1)
				(type default)
			)
			(layer "F.Fab")
		)
		(pad "1" smd circle
			(at -0.40005 0 90)
			(size 0 0)
			(layers "F.Cu" "F.Mask" "F.Paste")
			(net "PVCCFA_EHV_FIVRA_CPU0_VDD3")
		)
		(pad "2" smd circle
			(at 0.40005 0 90)
			(size 0 0)
			(layers "F.Cu" "F.Mask" "F.Paste")
			(net "GND")
		)
	)
	(footprint ""
		(layer "F.Cu")
		(at 468.164164 -61.047884 90)
		(property "Reference" "PC1649"
			(at 0 0 90)
			(layer "F.SilkS")
			(hide yes)
			(effects
				(font
					(size 1.27 1.27)
				)
			)
		)
		(property "Value" ""
			(at 0 0 90)
			(layer "F.Fab")
			(effects
				(font
					(size 1.27 1.27)
				)
			)
		)
		(duplicate_pad_numbers_are_jumpers no)
		(fp_line
			(start 0.7874 -0.4064)
			(end 0.7874 0.4064)
			(stroke
				(width 0.1524)
				(type default)
			)
			(layer "F.SilkS")
		)
		(fp_line
			(start -0.7874 -0.4064)
			(end 0.7874 -0.4064)
			(stroke
				(width 0.1524)
				(type default)
			)
			(layer "F.SilkS")
		)
		(fp_line
			(start 0.7874 0.4064)
			(end -0.7874 0.4064)
			(stroke
				(width 0.1524)
				(type default)
			)
			(layer "F.SilkS")
		)
		(fp_line
			(start -0.7874 0.4064)
			(end -0.7874 -0.4064)
			(stroke
				(width 0.1524)
				(type default)
			)
			(layer "F.SilkS")
		)
		(fp_line
			(start -0.12065 -0.305054)
			(end -0.12065 -0.2794)
			(stroke
				(width 0.1)
				(type default)
			)
			(layer "F.Fab")
		)
		(fp_line
			(start -0.67945 -0.305054)
			(end -0.12065 -0.305054)
			(stroke
				(width 0.1)
				(type default)
			)
			(layer "F.Fab")
		)
		(fp_line
			(start 0.67945 -0.3048)
			(end 0.67945 0.3048)
			(stroke
				(width 0.1)
				(type default)
			)
			(layer "F.Fab")
		)
		(fp_line
			(start 0.12065 -0.3048)
			(end 0.67945 -0.3048)
			(stroke
				(width 0.1)
				(type default)
			)
			(layer "F.Fab")
		)
		(fp_line
			(start 0.12065 -0.2794)
			(end 0.12065 -0.3048)
			(stroke
				(width 0.1)
				(type default)
			)
			(layer "F.Fab")
		)
		(fp_line
			(start -0.12065 -0.2794)
			(end 0.12065 -0.2794)
			(stroke
				(width 0.1)
				(type default)
			)
			(layer "F.Fab")
		)
		(fp_line
			(start 0.120396 0.2794)
			(end -0.12065 0.2794)
			(stroke
				(width 0.1)
				(type default)
			)
			(layer "F.Fab")
		)
		(fp_line
			(start -0.12065 0.2794)
			(end -0.12065 0.3048)
			(stroke
				(width 0.1)
				(type default)
			)
			(layer "F.Fab")
		)
		(fp_line
			(start 0.67945 0.3048)
			(end 0.120396 0.3048)
			(stroke
				(width 0.1)
				(type default)
			)
			(layer "F.Fab")
		)
		(fp_line
			(start 0.120396 0.3048)
			(end 0.120396 0.2794)
			(stroke
				(width 0.1)
				(type default)
			)
			(layer "F.Fab")
		)
		(fp_line
			(start -0.12065 0.3048)
			(end -0.67945 0.3048)
			(stroke
				(width 0.1)
				(type default)
			)
			(layer "F.Fab")
		)
		(fp_line
			(start -0.67945 0.3048)
			(end -0.67945 -0.305054)
			(stroke
				(width 0.1)
				(type default)
			)
			(layer "F.Fab")
		)
		(pad "1" smd circle
			(at -0.40005 0 90)
			(size 0 0)
			(layers "F.Cu" "F.Mask" "F.Paste")
			(net "P12V_AUX")
		)
		(pad "2" smd circle
			(at 0.40005 0 90)
			(size 0 0)
			(layers "F.Cu" "F.Mask" "F.Paste")
			(net "GND")
		)
	)
	(footprint ""
		(layer "F.Cu")
		(at 101.833934 -390.60374 180)
		(property "Reference" "R3397"
			(at 0 0 180)
			(layer "F.SilkS")
			(hide yes)
			(effects
				(font
					(size 1.27 1.27)
				)
			)
		)
		(property "Value" ""
			(at 0 0 180)
			(layer "F.Fab")
			(effects
				(font
					(size 1.27 1.27)
				)
			)
		)
		(duplicate_pad_numbers_are_jumpers no)
		(fp_line
			(start 0.7874 0.4064)
			(end -0.7874 0.4064)
			(stroke
				(width 0.1524)
				(type default)
			)
			(layer "F.SilkS")
		)
		(fp_line
			(start 0.7874 -0.4064)
			(end 0.7874 0.4064)
			(stroke
				(width 0.1524)
				(type default)
			)
			(layer "F.SilkS")
		)
		(fp_line
			(start -0.7874 0.4064)
			(end -0.7874 -0.4064)
			(stroke
				(width 0.1524)
				(type default)
			)
			(layer "F.SilkS")
		)
		(fp_line
			(start -0.7874 -0.4064)
			(end 0.7874 -0.4064)
			(stroke
				(width 0.1524)
				(type default)
			)
			(layer "F.SilkS")
		)
		(fp_line
			(start 0.67945 0.3048)
			(end 0.120396 0.3048)
			(stroke
				(width 0.1)
				(type default)
			)
			(layer "F.Fab")
		)
		(fp_line
			(start 0.67945 -0.3048)
			(end 0.67945 0.3048)
			(stroke
				(width 0.1)
				(type default)
			)
			(layer "F.Fab")
		)
		(fp_line
			(start 0.12065 -0.2794)
			(end 0.12065 -0.3048)
			(stroke
				(width 0.1)
				(type default)
			)
			(layer "F.Fab")
		)
		(fp_line
			(start 0.12065 -0.3048)
			(end 0.67945 -0.3048)
			(stroke
				(width 0.1)
				(type default)
			)
			(layer "F.Fab")
		)
		(fp_line
			(start 0.120396 0.3048)
			(end 0.120396 0.2794)
			(stroke
				(width 0.1)
				(type default)
			)
			(layer "F.Fab")
		)
		(fp_line
			(start 0.120396 0.2794)
			(end -0.12065 0.2794)
			(stroke
				(width 0.1)
				(type default)
			)
			(layer "F.Fab")
		)
		(fp_line
			(start -0.12065 0.3048)
			(end -0.67945 0.3048)
			(stroke
				(width 0.1)
				(type default)
			)
			(layer "F.Fab")
		)
		(fp_line
			(start -0.12065 0.2794)
			(end -0.12065 0.3048)
			(stroke
				(width 0.1)
				(type default)
			)
			(layer "F.Fab")
		)
		(fp_line
			(start -0.12065 -0.2794)
			(end 0.12065 -0.2794)
			(stroke
				(width 0.1)
				(type default)
			)
			(layer "F.Fab")
		)
		(fp_line
			(start -0.12065 -0.305054)
			(end -0.12065 -0.2794)
			(stroke
				(width 0.1)
				(type default)
			)
			(layer "F.Fab")
		)
		(fp_line
			(start -0.67945 0.3048)
			(end -0.67945 -0.305054)
			(stroke
				(width 0.1)
				(type default)
			)
			(layer "F.Fab")
		)
		(fp_line
			(start -0.67945 -0.305054)
			(end -0.12065 -0.305054)
			(stroke
				(width 0.1)
				(type default)
			)
			(layer "F.Fab")
		)
		(pad "1" smd circle
			(at -0.40005 0 180)
			(size 0 0)
			(layers "F.Cu" "F.Mask" "F.Paste")
			(net "GPU_NVS_PWR_BRAKE_N_R")
		)
		(pad "2" smd circle
			(at 0.40005 0 180)
			(size 0 0)
			(layers "F.Cu" "F.Mask" "F.Paste")
			(net "GPU_NVS_PWR_BRAKE_N_BUF")
		)
	)
	(footprint ""
		(layer "F.Cu")
		(at 52.423314 -144.267174 180)
		(property "Reference" "PC441"
			(at 0 0 180)
			(layer "F.SilkS")
			(hide yes)
			(effects
				(font
					(size 1.27 1.27)
				)
			)
		)
		(property "Value" ""
			(at 0 0 180)
			(layer "F.Fab")
			(effects
				(font
					(size 1.27 1.27)
				)
			)
		)
		(duplicate_pad_numbers_are_jumpers no)
		(fp_line
			(start 0.7874 0.4064)
			(end -0.7874 0.4064)
			(stroke
				(width 0.1524)
				(type default)
			)
			(layer "F.SilkS")
		)
		(fp_line
			(start 0.7874 -0.4064)
			(end 0.7874 0.4064)
			(stroke
				(width 0.1524)
				(type default)
			)
			(layer "F.SilkS")
		)
		(fp_line
			(start -0.7874 0.4064)
			(end -0.7874 -0.4064)
			(stroke
				(width 0.1524)
				(type default)
			)
			(layer "F.SilkS")
		)
		(fp_line
			(start -0.7874 -0.4064)
			(end 0.7874 -0.4064)
			(stroke
				(width 0.1524)
				(type default)
			)
			(layer "F.SilkS")
		)
		(fp_line
			(start 0.67945 0.3048)
			(end 0.120396 0.3048)
			(stroke
				(width 0.1)
				(type default)
			)
			(layer "F.Fab")
		)
		(fp_line
			(start 0.67945 -0.3048)
			(end 0.67945 0.3048)
			(stroke
				(width 0.1)
				(type default)
			)
			(layer "F.Fab")
		)
		(fp_line
			(start 0.12065 -0.2794)
			(end 0.12065 -0.3048)
			(stroke
				(width 0.1)
				(type default)
			)
			(layer "F.Fab")
		)
		(fp_line
			(start 0.12065 -0.3048)
			(end 0.67945 -0.3048)
			(stroke
				(width 0.1)
				(type default)
			)
			(layer "F.Fab")
		)
		(fp_line
			(start 0.120396 0.3048)
			(end 0.120396 0.2794)
			(stroke
				(width 0.1)
				(type default)
			)
			(layer "F.Fab")
		)
		(fp_line
			(start 0.120396 0.2794)
			(end -0.12065 0.2794)
			(stroke
				(width 0.1)
				(type default)
			)
			(layer "F.Fab")
		)
		(fp_line
			(start -0.12065 0.3048)
			(end -0.67945 0.3048)
			(stroke
				(width 0.1)
				(type default)
			)
			(layer "F.Fab")
		)
		(fp_line
			(start -0.12065 0.2794)
			(end -0.12065 0.3048)
			(stroke
				(width 0.1)
				(type default)
			)
			(layer "F.Fab")
		)
		(fp_line
			(start -0.12065 -0.2794)
			(end 0.12065 -0.2794)
			(stroke
				(width 0.1)
				(type default)
			)
			(layer "F.Fab")
		)
		(fp_line
			(start -0.12065 -0.305054)
			(end -0.12065 -0.2794)
			(stroke
				(width 0.1)
				(type default)
			)
			(layer "F.Fab")
		)
		(fp_line
			(start -0.67945 0.3048)
			(end -0.67945 -0.305054)
			(stroke
				(width 0.1)
				(type default)
			)
			(layer "F.Fab")
		)
		(fp_line
			(start -0.67945 -0.305054)
			(end -0.12065 -0.305054)
			(stroke
				(width 0.1)
				(type default)
			)
			(layer "F.Fab")
		)
		(pad "1" smd circle
			(at -0.40005 0 180)
			(size 0 0)
			(layers "F.Cu" "F.Mask" "F.Paste")
			(net "PVCCINFAON_CPU1_VDD2")
		)
		(pad "2" smd circle
			(at 0.40005 0 180)
			(size 0 0)
			(layers "F.Cu" "F.Mask" "F.Paste")
			(net "GND")
		)
	)
)
